# BASEBOARD_FAB2 (Tioga Pass) — schematic netlist excerpt (pin names and nets, part order shuffled) for the footprints in the layout excerpt that follows; sources: Cadence DE-HDL packaged netlist, KiCad conversion of Wiwynn_Tioga_Pass_MB.brd

C2L27  CAP_A  0.01UF 25V 10% X7R  pkg 0402V  page 173 : A = SATA6G_P5_TX_C_DP ; B = SATA6G_PCH_PCIE_UP_SATA_TXP<5>
R4P2  RES  49.9 1% CHIP  pkg 0402  page 21 : A = A_CPU0_PE3_RBIAS ; B = GND
C2U17  CAP  0.22UF 16V 10% X7R  pkg 0402  page 107 : A = P3E_CPU0_PE1_PCH_RXP<7> ; B = P3E_CPU0_PE1_SS_RXP<7>

(kicad_pcb
	(version 20260206)
	(generator "pcbnew")
	(generator_version "10.0")
	(general
		(thickness 1.6)
		(legacy_teardrops no)
	)
	(paper "A4")
	(title_block
		(title "Wiwynn_Tioga_Pass_MB.brd")
		(comment 1 "Tioga Pass / footprints 2839-2841 of 4770")
	)
	(layers
		(0 "F.Cu" signal "TOP")
		(4 "In1.Cu" signal "L2GND")
		(6 "In2.Cu" signal "L3")
		(8 "In3.Cu" signal "L4GND")
		(10 "In4.Cu" signal "L5")
		(12 "In5.Cu" signal "L6GND")
		(14 "In6.Cu" signal "L7VCC")
		(16 "In7.Cu" signal "L8VCC")
		(18 "In8.Cu" signal "L9GND")
		(20 "In9.Cu" signal "L10")
		(22 "In10.Cu" signal "L11GND")
		(24 "In11.Cu" signal "L12")
		(26 "In12.Cu" signal "L13GND")
		(2 "B.Cu" signal "BOTTOM")
		(9 "F.Adhes" user "F.Adhesive")
		(11 "B.Adhes" user "B.Adhesive")
		(13 "F.Paste" user "Package Geometry/Pastemask Top")
		(15 "B.Paste" user "Package Geometry/Pastemask Bottom")
		(5 "F.SilkS" user "Ref Des/Silkscreen Top")
		(7 "B.SilkS" user "Ref Des/Silkscreen Bottom")
		(1 "F.Mask" user "Board Geometry/Soldermask Top")
		(3 "B.Mask" user "Board Geometry/Soldermask Bottom")
		(17 "Dwgs.User" user "User.Drawings")
		(19 "Cmts.User" user "User.Comments")
		(21 "Eco1.User" user "User.Eco1")
		(23 "Eco2.User" user "User.Eco2")
		(25 "Edge.Cuts" user "Board Geometry/Outline")
		(27 "Margin" user)
		(31 "F.CrtYd" user "Package Geometry/Place Bound Top")
		(29 "B.CrtYd" user "Package Geometry/Place Bound Bottom")
		(35 "F.Fab" user "Ref Des/Assembly Top")
		(33 "B.Fab" user "Ref Des/Assembly Bottom")
	)
	(footprint ""
		(layer "B.Cu")
		(at 411.861 -145.415 -90)
		(property "Reference" "C2L27"
			(at 0 0 90)
			(layer "B.SilkS")
			(hide yes)
			(effects
				(font
					(size 1.27 1.27)
				)
				(justify mirror)
			)
		)
		(property "Value" ""
			(at 0 0 90)
			(layer "B.Fab")
			(effects
				(font
					(size 1.27 1.27)
				)
				(justify mirror)
			)
		)
		(duplicate_pad_numbers_are_jumpers no)
		(fp_poly
			(pts
				(xy -0.3048 -0.1016) (xy -0.3048 0.9906) (xy 0.3048 0.9906) (xy 0.3048 -0.1016)
			)
			(stroke
				(width 0)
				(type default)
			)
			(fill no)
			(layer "B.CrtYd")
		)
		(fp_line
			(start -0.3048 0.9906)
			(end -0.3048 -0.1016)
			(stroke
				(width 0.1)
				(type default)
			)
			(layer "B.Fab")
		)
		(fp_line
			(start 0.3048 0.9906)
			(end -0.3048 0.9906)
			(stroke
				(width 0.1)
				(type default)
			)
			(layer "B.Fab")
		)
		(fp_line
			(start -0.3048 -0.1016)
			(end 0.3048 -0.1016)
			(stroke
				(width 0.1)
				(type default)
			)
			(layer "B.Fab")
		)
		(fp_line
			(start 0.3048 -0.1016)
			(end 0.3048 0.9906)
			(stroke
				(width 0.1)
				(type default)
			)
			(layer "B.Fab")
		)
		(pad "1" smd rect
			(at 0 0 90)
			(size 0.508 0.508)
			(layers "B.Cu" "B.Mask" "B.Paste")
			(net "SATA6G_P5_TX_C_DP")
		)
		(pad "2" smd rect
			(at 0 0.889 90)
			(size 0.508 0.508)
			(layers "B.Cu" "B.Mask" "B.Paste")
			(net "SATA6G_PCH_PCIE_UP_SATA_TXP<5>")
		)
		(zone
			(layer "B.Cu")
			(hatch none 0.5)
			(connect_pads
				(clearance 0)
			)
			(min_thickness 0.25)
			(keepout
				(tracks not_allowed)
				(vias allowed)
				(pads allowed)
				(copperpour not_allowed)
				(footprints allowed)
			)
			(placement
				(enabled no)
				(sheetname "")
			)
			(fill
				(thermal_gap 0.5)
				(thermal_bridge_width 0.5)
				(island_removal_mode 0)
			)
			(polygon
				(pts
					(xy 411.226 -145.161) (xy 411.226 -145.669) (xy 411.607 -145.669) (xy 411.607 -145.161)
				)
			)
		)
		(zone
			(layer "B.Cu")
			(hatch none 0.5)
			(connect_pads
				(clearance 0)
			)
			(min_thickness 0.25)
			(keepout
				(tracks allowed)
				(vias not_allowed)
				(pads allowed)
				(copperpour not_allowed)
				(footprints allowed)
			)
			(placement
				(enabled no)
				(sheetname "")
			)
			(fill
				(thermal_gap 0.5)
				(thermal_bridge_width 0.5)
				(island_removal_mode 0)
			)
			(polygon
				(pts
					(xy 411.607 -145.161) (xy 411.607 -145.669) (xy 411.226 -145.669) (xy 411.226 -145.161)
				)
			)
		)
	)
	(footprint ""
		(layer "B.Cu")
		(at 352.904806 -61.257434)
		(property "Reference" "C2U17"
			(at 0 0 0)
			(layer "B.SilkS")
			(hide yes)
			(effects
				(font
					(size 1.27 1.27)
				)
				(justify mirror)
			)
		)
		(property "Value" ""
			(at 0 0 0)
			(layer "B.Fab")
			(effects
				(font
					(size 1.27 1.27)
				)
				(justify mirror)
			)
		)
		(duplicate_pad_numbers_are_jumpers no)
		(fp_poly
			(pts
				(xy -0.3048 -0.1016) (xy -0.3048 0.9906) (xy 0.3048 0.9906) (xy 0.3048 -0.1016)
			)
			(stroke
				(width 0)
				(type default)
			)
			(fill no)
			(layer "B.CrtYd")
		)
		(fp_line
			(start -0.3048 -0.1016)
			(end 0.3048 -0.1016)
			(stroke
				(width 0.1)
				(type default)
			)
			(layer "B.Fab")
		)
		(fp_line
			(start -0.3048 0.9906)
			(end -0.3048 -0.1016)
			(stroke
				(width 0.1)
				(type default)
			)
			(layer "B.Fab")
		)
		(fp_line
			(start 0.3048 -0.1016)
			(end 0.3048 0.9906)
			(stroke
				(width 0.1)
				(type default)
			)
			(layer "B.Fab")
		)
		(fp_line
			(start 0.3048 0.9906)
			(end -0.3048 0.9906)
			(stroke
				(width 0.1)
				(type default)
			)
			(layer "B.Fab")
		)
		(pad "1" smd rect
			(at 0 0 180)
			(size 0.508 0.508)
			(layers "B.Cu" "B.Mask" "B.Paste")
			(net "P3E_CPU0_PE1_PCH_RXP<7>")
		)
		(pad "2" smd rect
			(at 0 0.889 180)
			(size 0.508 0.508)
			(layers "B.Cu" "B.Mask" "B.Paste")
			(net "P3E_CPU0_PE1_SS_RXP<7>")
		)
		(zone
			(layer "B.Cu")
			(hatch none 0.5)
			(connect_pads
				(clearance 0)
			)
			(min_thickness 0.25)
			(keepout
				(tracks allowed)
				(vias not_allowed)
				(pads allowed)
				(copperpour not_allowed)
				(footprints allowed)
			)
			(placement
				(enabled no)
				(sheetname "")
			)
			(fill
				(thermal_gap 0.5)
				(thermal_bridge_width 0.5)
				(island_removal_mode 0)
			)
			(polygon
				(pts
					(xy 353.158806 -61.003434) (xy 352.650806 -61.003434) (xy 352.650806 -60.622434) (xy 353.158806 -60.622434)
				)
			)
		)
		(zone
			(layer "B.Cu")
			(hatch none 0.5)
			(connect_pads
				(clearance 0)
			)
			(min_thickness 0.25)
			(keepout
				(tracks not_allowed)
				(vias allowed)
				(pads allowed)
				(copperpour not_allowed)
				(footprints allowed)
			)
			(placement
				(enabled no)
				(sheetname "")
			)
			(fill
				(thermal_gap 0.5)
				(thermal_bridge_width 0.5)
				(island_removal_mode 0)
			)
			(polygon
				(pts
					(xy 353.158806 -60.622434) (xy 352.650806 -60.622434) (xy 352.650806 -61.003434) (xy 353.158806 -61.003434)
				)
			)
		)
	)
	(footprint ""
		(layer "B.Cu")
		(at 282.259024 -78.801214 -90)
		(property "Reference" "R4P2"
			(at 0 0 90)
			(layer "B.SilkS")
			(hide yes)
			(effects
				(font
					(size 1.27 1.27)
				)
				(justify mirror)
			)
		)
		(property "Value" ""
			(at 0 0 90)
			(layer "B.Fab")
			(effects
				(font
					(size 1.27 1.27)
				)
				(justify mirror)
			)
		)
		(duplicate_pad_numbers_are_jumpers no)
		(fp_rect
			(start 0.2794 0.9906)
			(end -0.2794 -0.1016)
			(stroke
				(width 0)
				(type default)
			)
			(fill no)
			(layer "B.CrtYd")
		)
		(fp_line
			(start -0.2794 0.9906)
			(end -0.2794 -0.1016)
			(stroke
				(width 0.1)
				(type default)
			)
			(layer "B.Fab")
		)
		(fp_line
			(start 0.2794 0.9906)
			(end -0.2794 0.9906)
			(stroke
				(width 0.1)
				(type default)
			)
			(layer "B.Fab")
		)
		(fp_line
			(start -0.2794 -0.1016)
			(end 0.2794 -0.1016)
			(stroke
				(width 0.1)
				(type default)
			)
			(layer "B.Fab")
		)
		(fp_line
			(start 0.2794 -0.1016)
			(end 0.2794 0.9906)
			(stroke
				(width 0.1)
				(type default)
			)
			(layer "B.Fab")
		)
		(pad "1" smd rect
			(at 0 0 90)
			(size 0.508 0.508)
			(layers "B.Cu" "B.Mask" "B.Paste")
			(net "A_CPU0_PE3_RBIAS")
		)
		(pad "2" smd rect
			(at 0 0.889 90)
			(size 0.508 0.508)
			(layers "B.Cu" "B.Mask" "B.Paste")
			(net "GND")
		)
		(zone
			(layer "B.Cu")
			(hatch none 0.5)
			(connect_pads
				(clearance 0)
			)
			(min_thickness 0.25)
			(keepout
				(tracks not_allowed)
				(vias allowed)
				(pads allowed)
				(copperpour not_allowed)
				(footprints allowed)
			)
			(placement
				(enabled no)
				(sheetname "")
			)
			(fill
				(thermal_gap 0.5)
				(thermal_bridge_width 0.5)
				(island_removal_mode 0)
			)
			(polygon
				(pts
					(xy 281.624024 -78.547214) (xy 282.005024 -78.547214) (xy 282.005024 -79.055214) (xy 281.624024 -79.055214)
				)
			)
		)
		(zone
			(layer "B.Cu")
			(hatch none 0.5)
			(connect_pads
				(clearance 0)
			)
			(min_thickness 0.25)
			(keepout
				(tracks allowed)
				(vias not_allowed)
				(pads allowed)
				(copperpour not_allowed)
				(footprints allowed)
			)
			(placement
				(enabled no)
				(sheetname "")
			)
			(fill
				(thermal_gap 0.5)
				(thermal_bridge_width 0.5)
				(island_removal_mode 0)
			)
			(polygon
				(pts
					(xy 281.624024 -78.547214) (xy 282.005024 -78.547214) (xy 282.005024 -79.055214) (xy 281.624024 -79.055214)
				)
			)
		)
	)
)
